FILE_TYPE = CONNECTIVITY;
{CONCEPT 1.4-P04 29-Mar-93}
0"NC";
1"GND\G\R SIZE";
2"A<SIZE-1..0>\NAC\I";
%"SYNONYM"
"1","(2100,2100)","0","/usr/tools/22/concept_lib/standard/standard.lib","1P";
;
NEEDS_NO_SIZE"TRUE"
BODY_TYPE"PLUMBING";
"A\NWC\NAC"1;
"A\NWC\NAC"2;
%"DRAWING"
"1","(2350,1750)","0","/usr/tools/22/concept_lib/standard/standard.lib","";
;
LAST_MODIFIED"Mon Oct  4 09:08:54 1993"
ABBREV"GND"
TITLE"GND";
END.
